FILE_TYPE = CONNECTIVITY;
{Allegro Design Entry HDL 16.6-p007 (v16-6-112F) 10/10/2012}
"PAGE_NUMBER" = 143;
0"NC";
1"GND\g";
2"GND\g";
3"IRQ_PCH_NIC_ALERT_N";
4"FM_ROMA<0>";
5"FM_BMC_DISABLE";
6"BMC_M_ODT";
7"BMC_M_DM0";
8"BMC_MIOZ";
9"BMC_M_VREFCA";
10"BMC_M_CS_N";
11"BMC_M_CLK_DP";
12"BMC_M_CKE";
13"FM_BMC_ENABLE_N";
14"BMC_M_A11";
15"BMC_M_A8";
16"BMC_M_BG0";
17"BMC_M_A5";
18"BMC_M_A4";
19"BMC_M_WE_N";
20"BMC_M_CAS_N";
21"BMC_M_A12";
22"TP_BMC_M_A15";
23"BMC_M_MACT_N";
24"BMC_M_A10";
25"BMC_M_A13";
26"BMC_M_DQS1_DN";
27"BMC_M_DM1";
28"BMC_M_CLK_DN";
29"BMC_M_RAS_N";
30"BMC_M_BA0";
31"BMC_M_A0";
32"BMC_M_BA1";
33"BMC_M_A1";
34"BMC_M_A3";
35"BMC_M_A2";
36"BMC_M_A6";
37"BMC_M_A7";
38"BMC_M_A9";
39"BMC_M_DQS0_DN";
40"BMC_M_DQS0_DP";
41"BMC_M_DQ1";
42"BMC_M_DQ3";
43"BMC_M_DQ5";
44"BMC_M_DQ7";
45"BMC_M_DQ9";
46"BMC_M_DQ11";
47"BMC_M_DQ13";
48"BMC_M_DQ15";
49"BMC_M_DQS1_DP";
50"BMC_M_DQ0";
51"BMC_M_DQ2";
52"BMC_M_DQ4";
53"BMC_M_DQ6";
54"BMC_M_DQ8";
55"BMC_M_DQ10";
56"BMC_M_DQ12";
57"BMC_M_DQ14";
%"GND"
"1","(-10250,-2200)","3","mstr_symbols","I54";
;
HDL_POWER"GND"
BODY_TYPE"PLUMBING"
CDS_LIB"mstr_symbols"
SIZE"1B"
VOLTAGE"0.0V";
"A\NAC"2;
%"CAP"
"1","(-10500,-2200)","3","mstr_discrete","I55";
;
CDS_SEC"1"
$SEC"1"
CDS_LOCATION"C25W22"
CDS_LIB"mstr_discrete"
BOM_COST"SM_CONTROLLER"
ROOM"BMC"
PART_NUMBER"A36096-030"
PACK_TYPE"0402LF"
TOLERANCE"10%"
MATERIAL"X7R"
VOLTAGE"16V"
LOCATION"C25W22"
VALUE"0.1UF";
"A"
$PN"1"9;
"B"
$PN"2"2;
%"GND"
"1","(-10250,-2150)","1","mstr_symbols","I57";
;
HDL_POWER"GND"
BODY_TYPE"PLUMBING"
VOLTAGE"0.0V"
SIZE"1B"
CDS_LIB"mstr_symbols";
"A\NAC"1;
%"RES"
"2","(-10925,-2150)","7","mstr_discrete","I58";
;
CDS_SEC"1"
$SEC"1"
CDS_LOCATION"R1T27"
WATTAGE"1/16W"
MATERIAL"CHIP"
PART_NUMBER"G21796-294"
ROOM"BMC_MEMORY"
BOM_COST"SM_MEM"
CDS_LIB"mstr_discrete"
TOLERANCE"1.0%"
VALUE"240"
PACK_TYPE"0402"
LOCATION"R1T27";
"A"
$PN"1"1;
"B"
$PN"2"8;
%"AST2520A1-GP-GP"
"1","(-12850,-1850)","0","w_hdl","I63";
;
CDS_SEC"1"
$SEC"1"
CDS_LOCATION"U25W4"
PART_NUMBER"071.2520A.M001"
PACK_TYPE"ASIC2-GB1"
CDS_LMAN_SYM_OUTLINE"-575,1050,575,-1050"
CDS_LIB"w_hdl"
LOCATION"U25W4"
VALUE"AST2520A1-GP-GP";
"MCS# \B"
$PN"AA12"10;
"MCKP"
$PN"AB11"11;
"MDQ8"
$PN"AA8"54;
"MDQ7"
$PN"V9"44;
"MRAS# \B"
$PN"W12"29;
"MWE# \B"
$PN"Y12"19;
"MDQ10"
$PN"Y7"55;
"MDQ11"
$PN"W8"46;
"MA14_MACT# \B"
$PN"Y15"23;
"MA13"
$PN"AB15"25;
"MDM0"
$PN"U8"7;
"MDQ12"
$PN"AA6"56;
"MDQ13"
$PN"W7"47;
"MDQ5"
$PN"Y9"43;
"MDQ6"
$PN"W9"53;
"MDQS0N"
$PN"AB10"39;
"MDQS0P"
$PN"AB9"40;
"MDQS1N"
$PN"AB6"26;
"MDQS1P"
$PN"AB7"49;
"MA0"
$PN"V13"31;
"MA1"
$PN"AB14"33;
"MA12"
$PN"Y14"21;
"MA2"
$PN"W14"35;
"MA3"
$PN"U14"34;
"MA4"
$PN"W15"18;
"MA5"
$PN"V15"17;
"MA6"
$PN"AB16"36;
"MA7"
$PN"AA16"37;
"MA8"
$PN"W16"15;
"MA9"
$PN"Y16"38;
"MBA0"
$PN"U12"30;
"MBA1"
$PN"Y13"32;
"MBA2_MBG0"
$PN"W13"16;
"MCKN"
$PN"AB12"28;
"MCKE"
$PN"Y11"12;
"MODT"
$PN"V11"6;
"MDQ9"
$PN"Y8"45;
"MVREF"
$PN"T9"9;
"MA11"
$PN"AA14"14;
"MA10"
$PN"U13"24;
"MCAS# \B"
$PN"AB13"20;
"MIOZ"
$PN"W11"8;
"MDM1"
$PN"AB8"27;
"MDQ14"
$PN"V7"57;
"MDQ15"
$PN"U7"48;
"MA15"
$PN"U15"22;
"MDQ0"
$PN"U10"50;
"MDQ1"
$PN"W10"41;
"MDQ2"
$PN"Y10"51;
"MDQ3"
$PN"AA10"42;
"MDQ4"
$PN"U9"52;
END.
